(kicad_pcb
	(version 20260206)
	(generator "pcbnew")
	(generator_version "10.0")
	(general
		(thickness 1.6)
		(legacy_teardrops no)
	)
	(paper "A4")
	(title_block
		(title "01162023_DA0F0TEBIF0_F0T_Expander_BD_F_brd_V02_OCP.brd")
		(comment 1 "Grand Teton / footprint 4451 of 9728 (PEX3), pads 1-116 of 2397")
	)
	(layers
		(0 "F.Cu" signal "TOP")
		(4 "In1.Cu" signal "GND")
		(6 "In2.Cu" signal "VCC")
		(8 "In3.Cu" signal "VCC1")
		(10 "In4.Cu" signal "GND1")
		(12 "In5.Cu" signal "IN1")
		(14 "In6.Cu" signal "GND2")
		(16 "In7.Cu" signal "IN2")
		(18 "In8.Cu" signal "GND3")
		(20 "In9.Cu" signal "IN3")
		(22 "In10.Cu" signal "GND4")
		(24 "In11.Cu" signal "IN4")
		(26 "In12.Cu" signal "GND5")
		(28 "In13.Cu" signal "IN5")
		(30 "In14.Cu" signal "GND6")
		(32 "In15.Cu" signal "IN6")
		(34 "In16.Cu" signal "GND7")
		(2 "B.Cu" signal "BOTTOM")
		(9 "F.Adhes" user "F.Adhesive")
		(11 "B.Adhes" user "B.Adhesive")
		(13 "F.Paste" user "Package Geometry/Pastemask Top")
		(15 "B.Paste" user "Package Geometry/Pastemask Bottom")
		(5 "F.SilkS" user "Ref Des/Silkscreen Top")
		(7 "B.SilkS" user "Ref Des/Silkscreen Bottom")
		(1 "F.Mask" user "Board Geometry/Soldermask Top")
		(3 "B.Mask" user "Board Geometry/Soldermask Bottom")
		(17 "Dwgs.User" user "User.Drawings")
		(19 "Cmts.User" user "User.Comments")
		(21 "Eco1.User" user "User.Eco1")
		(23 "Eco2.User" user "User.Eco2")
		(25 "Edge.Cuts" user "Board Geometry/Outline")
		(27 "Margin" user)
		(31 "F.CrtYd" user "Package Geometry/Place Bound Top")
		(29 "B.CrtYd" user "Package Geometry/Place Bound Bottom")
		(35 "F.Fab" user "Ref Des/Assembly Top")
		(33 "B.Fab" user "Ref Des/Assembly Bottom")
	)
	(footprint ""
		(layer "F.Cu")
		(at 407.949908 -295.89984)
		(property "Reference" "PEX3"
			(at -3.358642 35.5727 0)
			(unlocked yes)
			(layer "F.SilkS")
			(effects
				(font
					(size 2.032 1.524)
					(thickness 0.1524)
				)
				(justify left)
			)
		)
		(property "Value" ""
			(at 0 0 0)
			(layer "F.Fab")
			(effects
				(font
					(size 1.27 1.27)
				)
			)
		)
		(duplicate_pad_numbers_are_jumpers no)
		(pad "A2" smd circle
			(at -21.850096 -22.800056)
			(size 0.4572 0.4572)
			(layers "F.Cu" "F.Mask" "F.Paste")
			(net "GND")
		)
		(pad "A3" smd circle
			(at -20.899882 -22.800056)
			(size 0.4572 0.4572)
			(layers "F.Cu" "F.Mask" "F.Paste")
			(net "P5E_PEX3_STN7_RX_DN<123>")
		)
		(pad "A4" smd circle
			(at -19.949922 -22.800056)
			(size 0.4572 0.4572)
			(layers "F.Cu" "F.Mask" "F.Paste")
			(net "GND")
		)
		(pad "A5" smd circle
			(at -18.999962 -22.800056)
			(size 0.4572 0.4572)
			(layers "F.Cu" "F.Mask" "F.Paste")
			(net "P5E_PEX3_STN7_RX_DN<125>")
		)
		(pad "A6" smd circle
			(at -18.050002 -22.800056)
			(size 0.4572 0.4572)
			(layers "F.Cu" "F.Mask" "F.Paste")
			(net "GND")
		)
		(pad "A7" smd circle
			(at -17.100042 -22.800056)
			(size 0.4572 0.4572)
			(layers "F.Cu" "F.Mask" "F.Paste")
			(net "P5E_PEX3_STN7_RX_DN<127>")
		)
		(pad "A8" smd circle
			(at -16.150082 -22.800056)
			(size 0.4572 0.4572)
			(layers "F.Cu" "F.Mask" "F.Paste")
			(net "GND")
		)
		(pad "A9" smd circle
			(at -15.200122 -22.800056)
			(size 0.4572 0.4572)
			(layers "F.Cu" "F.Mask" "F.Paste")
			(net "P5E_PEX3_STN6_RX_DN<110>")
		)
		(pad "A10" smd circle
			(at -14.249908 -22.800056)
			(size 0.4572 0.4572)
			(layers "F.Cu" "F.Mask" "F.Paste")
			(net "GND")
		)
		(pad "A11" smd circle
			(at -13.299948 -22.800056)
			(size 0.4572 0.4572)
			(layers "F.Cu" "F.Mask" "F.Paste")
			(net "P5E_PEX3_STN6_RX_DN<108>")
		)
		(pad "A12" smd circle
			(at -12.349988 -22.800056)
			(size 0.4572 0.4572)
			(layers "F.Cu" "F.Mask" "F.Paste")
			(net "GND")
		)
		(pad "A13" smd circle
			(at -11.400028 -22.800056)
			(size 0.4572 0.4572)
			(layers "F.Cu" "F.Mask" "F.Paste")
			(net "P5E_PEX3_STN6_RX_DN<106>")
		)
		(pad "A14" smd circle
			(at -10.450068 -22.800056)
			(size 0.4572 0.4572)
			(layers "F.Cu" "F.Mask" "F.Paste")
			(net "GND")
		)
		(pad "A15" smd circle
			(at -9.500108 -22.800056)
			(size 0.4572 0.4572)
			(layers "F.Cu" "F.Mask" "F.Paste")
			(net "P5E_PEX3_STN6_RX_DN<104>")
		)
		(pad "A16" smd circle
			(at -8.549894 -22.800056)
			(size 0.4572 0.4572)
			(layers "F.Cu" "F.Mask" "F.Paste")
			(net "GND")
		)
		(pad "A17" smd circle
			(at -7.599934 -22.800056)
			(size 0.4572 0.4572)
			(layers "F.Cu" "F.Mask" "F.Paste")
			(net "P5E_PEX3_STN6_RX_DN<102>")
		)
		(pad "A18" smd circle
			(at -6.649974 -22.800056)
			(size 0.4572 0.4572)
			(layers "F.Cu" "F.Mask" "F.Paste")
			(net "GND")
		)
		(pad "A19" smd circle
			(at -5.700014 -22.800056)
			(size 0.4572 0.4572)
			(layers "F.Cu" "F.Mask" "F.Paste")
			(net "P5E_PEX3_STN6_RX_DN<100>")
		)
		(pad "A20" smd circle
			(at -4.750054 -22.800056)
			(size 0.4572 0.4572)
			(layers "F.Cu" "F.Mask" "F.Paste")
			(net "GND")
		)
		(pad "A21" smd circle
			(at -3.800094 -22.800056)
			(size 0.4572 0.4572)
			(layers "F.Cu" "F.Mask" "F.Paste")
			(net "P5E_PEX3_STN6_RX_DN<98>")
		)
		(pad "A22" smd circle
			(at -2.84988 -22.800056)
			(size 0.4572 0.4572)
			(layers "F.Cu" "F.Mask" "F.Paste")
			(net "GND")
		)
		(pad "A23" smd circle
			(at -1.89992 -22.800056)
			(size 0.4572 0.4572)
			(layers "F.Cu" "F.Mask" "F.Paste")
			(net "P5E_PEX3_STN6_RX_DN<96>")
		)
		(pad "A24" smd circle
			(at -0.94996 -22.800056)
			(size 0.4572 0.4572)
			(layers "F.Cu" "F.Mask" "F.Paste")
			(net "GND")
		)
		(pad "A25" smd circle
			(at 0 -22.800056)
			(size 0.4572 0.4572)
			(layers "F.Cu" "F.Mask" "F.Paste")
			(net "P5E_PEX3_STN5_RX_DN<81>")
		)
		(pad "A26" smd circle
			(at 0.94996 -22.800056)
			(size 0.4572 0.4572)
			(layers "F.Cu" "F.Mask" "F.Paste")
			(net "GND")
		)
		(pad "A27" smd circle
			(at 1.89992 -22.800056)
			(size 0.4572 0.4572)
			(layers "F.Cu" "F.Mask" "F.Paste")
			(net "P5E_PEX3_STN5_RX_DN<83>")
		)
		(pad "A28" smd circle
			(at 2.84988 -22.800056)
			(size 0.4572 0.4572)
			(layers "F.Cu" "F.Mask" "F.Paste")
			(net "GND")
		)
		(pad "A29" smd circle
			(at 3.800094 -22.800056)
			(size 0.4572 0.4572)
			(layers "F.Cu" "F.Mask" "F.Paste")
			(net "P5E_PEX3_STN5_RX_DN<85>")
		)
		(pad "A30" smd circle
			(at 4.750054 -22.800056)
			(size 0.4572 0.4572)
			(layers "F.Cu" "F.Mask" "F.Paste")
			(net "GND")
		)
		(pad "A31" smd circle
			(at 5.700014 -22.800056)
			(size 0.4572 0.4572)
			(layers "F.Cu" "F.Mask" "F.Paste")
			(net "P5E_PEX3_STN5_RX_DN<87>")
		)
		(pad "A32" smd circle
			(at 6.649974 -22.800056)
			(size 0.4572 0.4572)
			(layers "F.Cu" "F.Mask" "F.Paste")
			(net "GND")
		)
		(pad "A33" smd circle
			(at 7.599934 -22.800056)
			(size 0.4572 0.4572)
			(layers "F.Cu" "F.Mask" "F.Paste")
			(net "P5E_PEX3_STN5_RX_DN<89>")
		)
		(pad "A34" smd circle
			(at 8.549894 -22.800056)
			(size 0.4572 0.4572)
			(layers "F.Cu" "F.Mask" "F.Paste")
			(net "GND")
		)
		(pad "A35" smd circle
			(at 9.500108 -22.800056)
			(size 0.4572 0.4572)
			(layers "F.Cu" "F.Mask" "F.Paste")
			(net "P5E_PEX3_STN5_RX_DN<91>")
		)
		(pad "A36" smd circle
			(at 10.450068 -22.800056)
			(size 0.4572 0.4572)
			(layers "F.Cu" "F.Mask" "F.Paste")
			(net "GND")
		)
		(pad "A37" smd circle
			(at 11.400028 -22.800056)
			(size 0.4572 0.4572)
			(layers "F.Cu" "F.Mask" "F.Paste")
			(net "P5E_PEX3_STN5_RX_DN<93>")
		)
		(pad "A38" smd circle
			(at 12.349988 -22.800056)
			(size 0.4572 0.4572)
			(layers "F.Cu" "F.Mask" "F.Paste")
			(net "GND")
		)
		(pad "A39" smd circle
			(at 13.299948 -22.800056)
			(size 0.4572 0.4572)
			(layers "F.Cu" "F.Mask" "F.Paste")
			(net "P5E_PEX3_STN5_RX_DN<95>")
		)
		(pad "A40" smd circle
			(at 14.249908 -22.800056)
			(size 0.4572 0.4572)
			(layers "F.Cu" "F.Mask" "F.Paste")
			(net "GND")
		)
		(pad "A41" smd circle
			(at 15.200122 -22.800056)
			(size 0.4572 0.4572)
			(layers "F.Cu" "F.Mask" "F.Paste")
			(net "P5E_PEX3_STN4_RX_DN<78>")
		)
		(pad "A42" smd circle
			(at 16.150082 -22.800056)
			(size 0.4572 0.4572)
			(layers "F.Cu" "F.Mask" "F.Paste")
			(net "GND")
		)
		(pad "A43" smd circle
			(at 17.100042 -22.800056)
			(size 0.4572 0.4572)
			(layers "F.Cu" "F.Mask" "F.Paste")
			(net "P5E_PEX3_STN4_RX_DN<76>")
		)
		(pad "A44" smd circle
			(at 18.050002 -22.800056)
			(size 0.4572 0.4572)
			(layers "F.Cu" "F.Mask" "F.Paste")
			(net "GND")
		)
		(pad "A45" smd circle
			(at 18.999962 -22.800056)
			(size 0.4572 0.4572)
			(layers "F.Cu" "F.Mask" "F.Paste")
			(net "P5E_PEX3_STN4_RX_DN<74>")
		)
		(pad "A46" smd circle
			(at 19.949922 -22.800056)
			(size 0.4572 0.4572)
			(layers "F.Cu" "F.Mask" "F.Paste")
			(net "GND")
		)
		(pad "A47" smd circle
			(at 20.899882 -22.800056)
			(size 0.4572 0.4572)
			(layers "F.Cu" "F.Mask" "F.Paste")
			(net "P5E_PEX3_STN4_RX_DN<72>")
		)
		(pad "A48" smd circle
			(at 21.850096 -22.800056)
			(size 0.4572 0.4572)
			(layers "F.Cu" "F.Mask" "F.Paste")
			(net "GND")
		)
		(pad "AA1" smd circle
			(at -22.800056 -3.800094)
			(size 0.4572 0.4572)
			(layers "F.Cu" "F.Mask" "F.Paste")
			(net "CLK_100M_PEX3_REF_R_DN")
		)
		(pad "AA2" smd circle
			(at -21.850096 -3.800094)
			(size 0.4572 0.4572)
			(layers "F.Cu" "F.Mask" "F.Paste")
			(net "CLK_100M_PEX3_REF_R_DP")
		)
		(pad "AA3" smd circle
			(at -20.899882 -3.800094)
			(size 0.4572 0.4572)
			(layers "F.Cu" "F.Mask" "F.Paste")
			(net "GND")
		)
		(pad "AA4" smd circle
			(at -19.949922 -3.800094)
			(size 0.4572 0.4572)
			(layers "F.Cu" "F.Mask" "F.Paste")
			(net "GND")
		)
		(pad "AA5" smd circle
			(at -18.999962 -3.800094)
			(size 0.4572 0.4572)
			(layers "F.Cu" "F.Mask" "F.Paste")
			(net "GND")
		)
		(pad "AA6" smd circle
			(at -18.050002 -3.800094)
			(size 0.4572 0.4572)
			(layers "F.Cu" "F.Mask" "F.Paste")
			(net "GND")
		)
		(pad "AA7" smd circle
			(at -17.100042 -3.800094)
			(size 0.4572 0.4572)
			(layers "F.Cu" "F.Mask" "F.Paste")
			(net "GND")
		)
		(pad "AA8" smd circle
			(at -16.150082 -3.800094)
			(size 0.4572 0.4572)
			(layers "F.Cu" "F.Mask" "F.Paste")
			(net "GND")
		)
		(pad "AA9" smd circle
			(at -15.200122 -3.800094)
			(size 0.4572 0.4572)
			(layers "F.Cu" "F.Mask" "F.Paste")
			(net "GND")
		)
		(pad "AA10" smd circle
			(at -14.249908 -3.800094)
			(size 0.4572 0.4572)
			(layers "F.Cu" "F.Mask" "F.Paste")
			(net "P1V8_VDDA_PEX3")
		)
		(pad "AA11" smd circle
			(at -13.299948 -3.800094)
			(size 0.4572 0.4572)
			(layers "F.Cu" "F.Mask" "F.Paste")
			(net "GND")
		)
		(pad "AA12" smd circle
			(at -12.349988 -3.800094)
			(size 0.4572 0.4572)
			(layers "F.Cu" "F.Mask" "F.Paste")
			(net "GND")
		)
		(pad "AA13" smd circle
			(at -11.400028 -3.800094)
			(size 0.4572 0.4572)
			(layers "F.Cu" "F.Mask" "F.Paste")
			(net "PCEPLL0_VDDA18_PEX3")
		)
		(pad "AA14" smd circle
			(at -10.450068 -3.800094)
			(size 0.4572 0.4572)
			(layers "F.Cu" "F.Mask" "F.Paste")
			(net "GND")
		)
		(pad "AA15" smd circle
			(at -9.500108 -3.800094)
			(size 0.4572 0.4572)
			(layers "F.Cu" "F.Mask" "F.Paste")
			(net "P0V8_PEX3")
		)
		(pad "AA16" smd circle
			(at -8.549894 -3.800094)
			(size 0.4572 0.4572)
			(layers "F.Cu" "F.Mask" "F.Paste")
			(net "GND")
		)
		(pad "AA17" smd circle
			(at -7.599934 -3.800094)
			(size 0.4572 0.4572)
			(layers "F.Cu" "F.Mask" "F.Paste")
			(net "GND")
		)
		(pad "AA18" smd circle
			(at -6.649974 -3.800094)
			(size 0.4572 0.4572)
			(layers "F.Cu" "F.Mask" "F.Paste")
			(net "GND")
		)
		(pad "AA19" smd circle
			(at -5.700014 -3.800094)
			(size 0.4572 0.4572)
			(layers "F.Cu" "F.Mask" "F.Paste")
			(net "GND")
		)
		(pad "AA20" smd circle
			(at -4.750054 -3.800094)
			(size 0.4572 0.4572)
			(layers "F.Cu" "F.Mask" "F.Paste")
			(net "GND")
		)
		(pad "AA21" smd circle
			(at -3.800094 -3.800094)
			(size 0.4572 0.4572)
			(layers "F.Cu" "F.Mask" "F.Paste")
			(net "GND")
		)
		(pad "AA22" smd circle
			(at -2.84988 -3.800094)
			(size 0.4572 0.4572)
			(layers "F.Cu" "F.Mask" "F.Paste")
			(net "GND")
		)
		(pad "AA23" smd circle
			(at -1.89992 -3.800094)
			(size 0.4572 0.4572)
			(layers "F.Cu" "F.Mask" "F.Paste")
			(net "GND")
		)
		(pad "AA24" smd circle
			(at -0.94996 -3.800094)
			(size 0.4572 0.4572)
			(layers "F.Cu" "F.Mask" "F.Paste")
			(net "GND")
		)
		(pad "AA25" smd circle
			(at 0 -3.800094)
			(size 0.4572 0.4572)
			(layers "F.Cu" "F.Mask" "F.Paste")
			(net "GND")
		)
		(pad "AA26" smd circle
			(at 0.94996 -3.800094)
			(size 0.4572 0.4572)
			(layers "F.Cu" "F.Mask" "F.Paste")
			(net "GND")
		)
		(pad "AA27" smd circle
			(at 1.89992 -3.800094)
			(size 0.4572 0.4572)
			(layers "F.Cu" "F.Mask" "F.Paste")
			(net "GND")
		)
		(pad "AA28" smd circle
			(at 2.84988 -3.800094)
			(size 0.4572 0.4572)
			(layers "F.Cu" "F.Mask" "F.Paste")
			(net "GND")
		)
		(pad "AA29" smd circle
			(at 3.800094 -3.800094)
			(size 0.4572 0.4572)
			(layers "F.Cu" "F.Mask" "F.Paste")
			(net "GND")
		)
		(pad "AA30" smd circle
			(at 4.750054 -3.800094)
			(size 0.4572 0.4572)
			(layers "F.Cu" "F.Mask" "F.Paste")
			(net "GND")
		)
		(pad "AA31" smd circle
			(at 5.700014 -3.800094)
			(size 0.4572 0.4572)
			(layers "F.Cu" "F.Mask" "F.Paste")
			(net "GND")
		)
		(pad "AA32" smd circle
			(at 6.649974 -3.800094)
			(size 0.4572 0.4572)
			(layers "F.Cu" "F.Mask" "F.Paste")
			(net "GND")
		)
		(pad "AA33" smd circle
			(at 7.599934 -3.800094)
			(size 0.4572 0.4572)
			(layers "F.Cu" "F.Mask" "F.Paste")
			(net "GND")
		)
		(pad "AA34" smd circle
			(at 8.549894 -3.800094)
			(size 0.4572 0.4572)
			(layers "F.Cu" "F.Mask" "F.Paste")
			(net "P1V8_VDDA_PEX3")
		)
		(pad "AA35" smd circle
			(at 9.500108 -3.800094)
			(size 0.4572 0.4572)
			(layers "F.Cu" "F.Mask" "F.Paste")
			(net "Net_537")
		)
		(pad "AA36" smd circle
			(at 10.450068 -3.800094)
			(size 0.4572 0.4572)
			(layers "F.Cu" "F.Mask" "F.Paste")
			(net "GND")
		)
		(pad "AA37" smd circle
			(at 11.400028 -3.800094)
			(size 0.4572 0.4572)
			(layers "F.Cu" "F.Mask" "F.Paste")
			(net "P1V8_VDDA_PEX3")
		)
		(pad "AA38" smd circle
			(at 12.349988 -3.800094)
			(size 0.4572 0.4572)
			(layers "F.Cu" "F.Mask" "F.Paste")
			(net "GND")
		)
		(pad "AA39" smd circle
			(at 13.299948 -3.800094)
			(size 0.4572 0.4572)
			(layers "F.Cu" "F.Mask" "F.Paste")
			(net "PEX3_ADCTEMP_VINP1")
		)
		(pad "AA40" smd circle
			(at 14.249908 -3.800094)
			(size 0.4572 0.4572)
			(layers "F.Cu" "F.Mask" "F.Paste")
			(net "GND")
		)
		(pad "AA41" smd circle
			(at 15.200122 -3.800094)
			(size 0.4572 0.4572)
			(layers "F.Cu" "F.Mask" "F.Paste")
			(net "GND")
		)
		(pad "AA42" smd circle
			(at 16.150082 -3.800094)
			(size 0.4572 0.4572)
			(layers "F.Cu" "F.Mask" "F.Paste")
			(net "GND")
		)
		(pad "AA43" smd circle
			(at 17.100042 -3.800094)
			(size 0.4572 0.4572)
			(layers "F.Cu" "F.Mask" "F.Paste")
			(net "Net_1521")
		)
		(pad "AA44" smd circle
			(at 18.050002 -3.800094)
			(size 0.4572 0.4572)
			(layers "F.Cu" "F.Mask" "F.Paste")
			(net "Net_1568")
		)
		(pad "AA45" smd circle
			(at 18.999962 -3.800094)
			(size 0.4572 0.4572)
			(layers "F.Cu" "F.Mask" "F.Paste")
			(net "GND")
		)
		(pad "AA46" smd circle
			(at 19.949922 -3.800094)
			(size 0.4572 0.4572)
			(layers "F.Cu" "F.Mask" "F.Paste")
			(net "Net_1490")
		)
		(pad "AA47" smd circle
			(at 20.899882 -3.800094)
			(size 0.4572 0.4572)
			(layers "F.Cu" "F.Mask" "F.Paste")
			(net "Net_1476")
		)
		(pad "AA48" smd circle
			(at 21.850096 -3.800094)
			(size 0.4572 0.4572)
			(layers "F.Cu" "F.Mask" "F.Paste")
			(net "GND")
		)
		(pad "AA49" smd circle
			(at 22.800056 -3.800094)
			(size 0.4572 0.4572)
			(layers "F.Cu" "F.Mask" "F.Paste")
			(net "GND")
		)
		(pad "AB1" smd circle
			(at -22.800056 -2.84988)
			(size 0.4572 0.4572)
			(layers "F.Cu" "F.Mask" "F.Paste")
			(net "GND")
		)
		(pad "AB2" smd circle
			(at -21.850096 -2.84988)
			(size 0.4572 0.4572)
			(layers "F.Cu" "F.Mask" "F.Paste")
			(net "GND")
		)
		(pad "AB3" smd circle
			(at -20.899882 -2.84988)
			(size 0.4572 0.4572)
			(layers "F.Cu" "F.Mask" "F.Paste")
			(net "GND")
		)
		(pad "AB4" smd circle
			(at -19.949922 -2.84988)
			(size 0.4572 0.4572)
			(layers "F.Cu" "F.Mask" "F.Paste")
			(net "CLK_100M_DB800ZL_PEX3_S0_R_DN")
		)
		(pad "AB5" smd circle
			(at -18.999962 -2.84988)
			(size 0.4572 0.4572)
			(layers "F.Cu" "F.Mask" "F.Paste")
			(net "CLK_100M_DB800ZL_PEX3_S0_R_DP")
		)
		(pad "AB6" smd circle
			(at -18.050002 -2.84988)
			(size 0.4572 0.4572)
			(layers "F.Cu" "F.Mask" "F.Paste")
			(net "GND")
		)
		(pad "AB7" smd circle
			(at -17.100042 -2.84988)
			(size 0.4572 0.4572)
			(layers "F.Cu" "F.Mask" "F.Paste")
			(net "Net_5486")
		)
		(pad "AB8" smd circle
			(at -16.150082 -2.84988)
			(size 0.4572 0.4572)
			(layers "F.Cu" "F.Mask" "F.Paste")
			(net "Net_5485")
		)
		(pad "AB9" smd circle
			(at -15.200122 -2.84988)
			(size 0.4572 0.4572)
			(layers "F.Cu" "F.Mask" "F.Paste")
			(net "GND")
		)
		(pad "AB10" smd circle
			(at -14.249908 -2.84988)
			(size 0.4572 0.4572)
			(layers "F.Cu" "F.Mask" "F.Paste")
			(net "P1V8_VDDA_PEX3")
		)
		(pad "AB11" smd circle
			(at -13.299948 -2.84988)
			(size 0.4572 0.4572)
			(layers "F.Cu" "F.Mask" "F.Paste")
			(net "GND")
		)
		(pad "AB12" smd circle
			(at -12.349988 -2.84988)
			(size 0.4572 0.4572)
			(layers "F.Cu" "F.Mask" "F.Paste")
			(net "PCEPLL1_VDDA18_PEX3")
		)
		(pad "AB13" smd circle
			(at -11.400028 -2.84988)
			(size 0.4572 0.4572)
			(layers "F.Cu" "F.Mask" "F.Paste")
			(net "GND")
		)
		(pad "AB14" smd circle
			(at -10.450068 -2.84988)
			(size 0.4572 0.4572)
			(layers "F.Cu" "F.Mask" "F.Paste")
			(net "P0V8_PEX3")
		)
		(pad "AB15" smd circle
			(at -9.500108 -2.84988)
			(size 0.4572 0.4572)
			(layers "F.Cu" "F.Mask" "F.Paste")
			(net "GND")
		)
		(pad "AB16" smd circle
			(at -8.549894 -2.84988)
			(size 0.4572 0.4572)
			(layers "F.Cu" "F.Mask" "F.Paste")
			(net "P0V8_SERDES_VDDA_PEX3")
		)
		(pad "AB17" smd circle
			(at -7.599934 -2.84988)
			(size 0.4572 0.4572)
			(layers "F.Cu" "F.Mask" "F.Paste")
			(net "P0V8_SERDES_VDDA_PEX3")
		)
		(pad "AB18" smd circle
			(at -6.649974 -2.84988)
			(size 0.4572 0.4572)
			(layers "F.Cu" "F.Mask" "F.Paste")
			(net "P0V8_SERDES_VDDA_PEX3")
		)
		(pad "AB19" smd circle
			(at -5.700014 -2.84988)
			(size 0.4572 0.4572)
			(layers "F.Cu" "F.Mask" "F.Paste")
			(net "P0V8_SERDES_VDDA_PEX3")
		)
		(pad "AB20" smd circle
			(at -4.750054 -2.84988)
			(size 0.4572 0.4572)
			(layers "F.Cu" "F.Mask" "F.Paste")
			(net "P0V8_SERDES_VDDA_PEX3")
		)
	)
)
